# S9S_MB_2U (Grand Teton) — schematic netlist excerpt (pin names and nets, part order shuffled) for the footprints in the layout excerpt that follows; sources: Cadence DE-HDL packaged netlist, KiCad conversion of 03242023_DA0F0TMBIJ0_F0T_Motherboard_J_brd_V01_OCP.brd

R747  Q_RES  150 1% CHIP  pkg 0402LF  page 132 : A = P1V05_PCH_AUX ; B = JTAG_DBP_TDO_PCH

(kicad_pcb
	(version 20260206)
	(generator "pcbnew")
	(generator_version "10.0")
	(general
		(thickness 1.6)
		(legacy_teardrops no)
	)
	(paper "A4")
	(title_block
		(title "03242023_DA0F0TMBIJ0_F0T_Motherboard_J_brd_V01_OCP.brd")
		(comment 1 "Grand Teton / footprints 3728-3728 of 6105")
	)
	(layers
		(0 "F.Cu" signal "TOP")
		(4 "In1.Cu" signal "GND")
		(6 "In2.Cu" signal "IN1")
		(8 "In3.Cu" signal "GND1")
		(10 "In4.Cu" signal "IN2")
		(12 "In5.Cu" signal "GND2")
		(14 "In6.Cu" signal "IN3")
		(16 "In7.Cu" signal "GND3")
		(18 "In8.Cu" signal "VCC")
		(20 "In9.Cu" signal "VCC1")
		(22 "In10.Cu" signal "GND4")
		(24 "In11.Cu" signal "IN4")
		(26 "In12.Cu" signal "GND5")
		(28 "In13.Cu" signal "IN5")
		(30 "In14.Cu" signal "GND6")
		(32 "In15.Cu" signal "IN6")
		(34 "In16.Cu" signal "GND7")
		(2 "B.Cu" signal "BOTTOM")
		(9 "F.Adhes" user "F.Adhesive")
		(11 "B.Adhes" user "B.Adhesive")
		(13 "F.Paste" user "Package Geometry/Pastemask Top")
		(15 "B.Paste" user "Package Geometry/Pastemask Bottom")
		(5 "F.SilkS" user "Ref Des/Silkscreen Top")
		(7 "B.SilkS" user "Ref Des/Silkscreen Bottom")
		(1 "F.Mask" user "Board Geometry/Soldermask Top")
		(3 "B.Mask" user "Board Geometry/Soldermask Bottom")
		(17 "Dwgs.User" user "User.Drawings")
		(19 "Cmts.User" user "User.Comments")
		(21 "Eco1.User" user "User.Eco1")
		(23 "Eco2.User" user "User.Eco2")
		(25 "Edge.Cuts" user "Board Geometry/Outline")
		(27 "Margin" user)
		(31 "F.CrtYd" user "Package Geometry/Place Bound Top")
		(29 "B.CrtYd" user "Package Geometry/Place Bound Bottom")
		(35 "F.Fab" user "Ref Des/Assembly Top")
		(33 "B.Fab" user "Ref Des/Assembly Bottom")
	)
	(footprint ""
		(layer "F.Cu")
		(at 377.541282 -59.295792 180)
		(property "Reference" "R747"
			(at 0 0 180)
			(layer "F.SilkS")
			(hide yes)
			(effects
				(font
					(size 1.27 1.27)
				)
			)
		)
		(property "Value" ""
			(at 0 0 180)
			(layer "F.Fab")
			(effects
				(font
					(size 1.27 1.27)
				)
			)
		)
		(duplicate_pad_numbers_are_jumpers no)
		(fp_line
			(start 0.7874 0.4064)
			(end -0.7874 0.4064)
			(stroke
				(width 0.1524)
				(type default)
			)
			(layer "F.SilkS")
		)
		(fp_line
			(start 0.7874 -0.4064)
			(end 0.7874 0.4064)
			(stroke
				(width 0.1524)
				(type default)
			)
			(layer "F.SilkS")
		)
		(fp_line
			(start -0.7874 0.4064)
			(end -0.7874 -0.4064)
			(stroke
				(width 0.1524)
				(type default)
			)
			(layer "F.SilkS")
		)
		(fp_line
			(start -0.7874 -0.4064)
			(end 0.7874 -0.4064)
			(stroke
				(width 0.1524)
				(type default)
			)
			(layer "F.SilkS")
		)
		(fp_line
			(start 0.67945 0.3048)
			(end 0.120396 0.3048)
			(stroke
				(width 0.1)
				(type default)
			)
			(layer "F.Fab")
		)
		(fp_line
			(start 0.67945 -0.3048)
			(end 0.67945 0.3048)
			(stroke
				(width 0.1)
				(type default)
			)
			(layer "F.Fab")
		)
		(fp_line
			(start 0.12065 -0.2794)
			(end 0.12065 -0.3048)
			(stroke
				(width 0.1)
				(type default)
			)
			(layer "F.Fab")
		)
		(fp_line
			(start 0.12065 -0.3048)
			(end 0.67945 -0.3048)
			(stroke
				(width 0.1)
				(type default)
			)
			(layer "F.Fab")
		)
		(fp_line
			(start 0.120396 0.3048)
			(end 0.120396 0.2794)
			(stroke
				(width 0.1)
				(type default)
			)
			(layer "F.Fab")
		)
		(fp_line
			(start 0.120396 0.2794)
			(end -0.12065 0.2794)
			(stroke
				(width 0.1)
				(type default)
			)
			(layer "F.Fab")
		)
		(fp_line
			(start -0.12065 0.3048)
			(end -0.67945 0.3048)
			(stroke
				(width 0.1)
				(type default)
			)
			(layer "F.Fab")
		)
		(fp_line
			(start -0.12065 0.2794)
			(end -0.12065 0.3048)
			(stroke
				(width 0.1)
				(type default)
			)
			(layer "F.Fab")
		)
		(fp_line
			(start -0.12065 -0.2794)
			(end 0.12065 -0.2794)
			(stroke
				(width 0.1)
				(type default)
			)
			(layer "F.Fab")
		)
		(fp_line
			(start -0.12065 -0.305054)
			(end -0.12065 -0.2794)
			(stroke
				(width 0.1)
				(type default)
			)
			(layer "F.Fab")
		)
		(fp_line
			(start -0.67945 0.3048)
			(end -0.67945 -0.305054)
			(stroke
				(width 0.1)
				(type default)
			)
			(layer "F.Fab")
		)
		(fp_line
			(start -0.67945 -0.305054)
			(end -0.12065 -0.305054)
			(stroke
				(width 0.1)
				(type default)
			)
			(layer "F.Fab")
		)
		(pad "1" smd circle
			(at -0.40005 0 180)
			(size 0 0)
			(layers "F.Cu" "F.Mask" "F.Paste")
			(net "P1V05_PCH_AUX")
		)
		(pad "2" smd circle
			(at 0.40005 0 180)
			(size 0 0)
			(layers "F.Cu" "F.Mask" "F.Paste")
			(net "JTAG_DBP_TDO_PCH")
		)
	)
)
